# BASEBOARD_FAB2 (Tioga Pass) — schematic netlist excerpt (pin names and nets, part order shuffled) for the footprints in the layout excerpt that follows; sources: Cadence DE-HDL packaged netlist, KiCad conversion of Wiwynn_Tioga_Pass_MB.brd

R8F13  RES  4.75K 1% CHIP  pkg 0402  page 162 : A = P3V3_STBY ; B = SPI_BMC_BT_CS_N
R9A17  RES  1.00K 1% CHIP  pkg 0402  page 111 : A = XDP_ITP_PMODE ; B = P1V05_PCH_STBY
R9A11  RES  150.0 1% CHIP  pkg 0402  page 112 : A = P1V05_PCH_STBY ; B = XDP_TDO

(kicad_pcb
	(version 20260206)
	(generator "pcbnew")
	(generator_version "10.0")
	(general
		(thickness 1.6)
		(legacy_teardrops no)
	)
	(paper "A4")
	(title_block
		(title "Wiwynn_Tioga_Pass_MB.brd")
		(comment 1 "Tioga Pass / footprints 2402-2404 of 4770")
	)
	(layers
		(0 "F.Cu" signal "TOP")
		(4 "In1.Cu" signal "L2GND")
		(6 "In2.Cu" signal "L3")
		(8 "In3.Cu" signal "L4GND")
		(10 "In4.Cu" signal "L5")
		(12 "In5.Cu" signal "L6GND")
		(14 "In6.Cu" signal "L7VCC")
		(16 "In7.Cu" signal "L8VCC")
		(18 "In8.Cu" signal "L9GND")
		(20 "In9.Cu" signal "L10")
		(22 "In10.Cu" signal "L11GND")
		(24 "In11.Cu" signal "L12")
		(26 "In12.Cu" signal "L13GND")
		(2 "B.Cu" signal "BOTTOM")
		(9 "F.Adhes" user "F.Adhesive")
		(11 "B.Adhes" user "B.Adhesive")
		(13 "F.Paste" user "Package Geometry/Pastemask Top")
		(15 "B.Paste" user "Package Geometry/Pastemask Bottom")
		(5 "F.SilkS" user "Ref Des/Silkscreen Top")
		(7 "B.SilkS" user "Ref Des/Silkscreen Bottom")
		(1 "F.Mask" user "Board Geometry/Soldermask Top")
		(3 "B.Mask" user "Board Geometry/Soldermask Bottom")
		(17 "Dwgs.User" user "User.Drawings")
		(19 "Cmts.User" user "User.Comments")
		(21 "Eco1.User" user "User.Eco1")
		(23 "Eco2.User" user "User.Eco2")
		(25 "Edge.Cuts" user "Board Geometry/Outline")
		(27 "Margin" user)
		(31 "F.CrtYd" user "Package Geometry/Place Bound Top")
		(29 "B.CrtYd" user "Package Geometry/Place Bound Bottom")
		(35 "F.Fab" user "Ref Des/Assembly Top")
		(33 "B.Fab" user "Ref Des/Assembly Bottom")
	)
	(footprint ""
		(layer "B.Cu")
		(at 453.6948 -147.5486 90)
		(property "Reference" "R9A11"
			(at 0 0 90)
			(layer "B.SilkS")
			(hide yes)
			(effects
				(font
					(size 1.27 1.27)
				)
				(justify mirror)
			)
		)
		(property "Value" ""
			(at 0 0 90)
			(layer "B.Fab")
			(effects
				(font
					(size 1.27 1.27)
				)
				(justify mirror)
			)
		)
		(duplicate_pad_numbers_are_jumpers no)
		(fp_poly
			(pts
				(xy 0.2794 -0.1016) (xy -0.2794 -0.1016) (xy -0.2794 0.9906) (xy 0.2794 0.9906)
			)
			(stroke
				(width 0)
				(type default)
			)
			(fill no)
			(layer "B.CrtYd")
		)
		(fp_line
			(start 0.2794 -0.1016)
			(end 0.2794 0.9906)
			(stroke
				(width 0.1)
				(type default)
			)
			(layer "B.Fab")
		)
		(fp_line
			(start -0.2794 -0.1016)
			(end 0.2794 -0.1016)
			(stroke
				(width 0.1)
				(type default)
			)
			(layer "B.Fab")
		)
		(fp_line
			(start 0.2794 0.9906)
			(end -0.2794 0.9906)
			(stroke
				(width 0.1)
				(type default)
			)
			(layer "B.Fab")
		)
		(fp_line
			(start -0.2794 0.9906)
			(end -0.2794 -0.1016)
			(stroke
				(width 0.1)
				(type default)
			)
			(layer "B.Fab")
		)
		(pad "1" smd rect
			(at 0 0 270)
			(size 0.508 0.508)
			(layers "B.Cu" "B.Mask" "B.Paste")
			(net "P1V05_PCH_STBY")
		)
		(pad "2" smd rect
			(at 0 0.889 270)
			(size 0.508 0.508)
			(layers "B.Cu" "B.Mask" "B.Paste")
			(net "XDP_TDO")
		)
		(zone
			(layer "B.Cu")
			(hatch none 0.5)
			(connect_pads
				(clearance 0)
			)
			(min_thickness 0.25)
			(keepout
				(tracks allowed)
				(vias not_allowed)
				(pads allowed)
				(copperpour not_allowed)
				(footprints allowed)
			)
			(placement
				(enabled no)
				(sheetname "")
			)
			(fill
				(thermal_gap 0.5)
				(thermal_bridge_width 0.5)
				(island_removal_mode 0)
			)
			(polygon
				(pts
					(xy 453.9488 -147.8026) (xy 453.9488 -147.2946) (xy 454.3298 -147.2946) (xy 454.3298 -147.8026)
				)
			)
		)
		(zone
			(layer "B.Cu")
			(hatch none 0.5)
			(connect_pads
				(clearance 0)
			)
			(min_thickness 0.25)
			(keepout
				(tracks not_allowed)
				(vias allowed)
				(pads allowed)
				(copperpour not_allowed)
				(footprints allowed)
			)
			(placement
				(enabled no)
				(sheetname "")
			)
			(fill
				(thermal_gap 0.5)
				(thermal_bridge_width 0.5)
				(island_removal_mode 0)
			)
			(polygon
				(pts
					(xy 454.3298 -147.8026) (xy 454.3298 -147.2946) (xy 453.9488 -147.2946) (xy 453.9488 -147.8026)
				)
			)
		)
	)
	(footprint ""
		(layer "B.Cu")
		(at 367.646712 -37.856922)
		(property "Reference" "R8F13"
			(at 0 0 0)
			(layer "B.SilkS")
			(hide yes)
			(effects
				(font
					(size 1.27 1.27)
				)
				(justify mirror)
			)
		)
		(property "Value" ""
			(at 0 0 0)
			(layer "B.Fab")
			(effects
				(font
					(size 1.27 1.27)
				)
				(justify mirror)
			)
		)
		(duplicate_pad_numbers_are_jumpers no)
		(fp_poly
			(pts
				(xy 0.2794 -0.1016) (xy -0.2794 -0.1016) (xy -0.2794 0.9906) (xy 0.2794 0.9906)
			)
			(stroke
				(width 0)
				(type default)
			)
			(fill no)
			(layer "B.CrtYd")
		)
		(fp_line
			(start -0.2794 -0.1016)
			(end 0.2794 -0.1016)
			(stroke
				(width 0.1)
				(type default)
			)
			(layer "B.Fab")
		)
		(fp_line
			(start -0.2794 0.9906)
			(end -0.2794 -0.1016)
			(stroke
				(width 0.1)
				(type default)
			)
			(layer "B.Fab")
		)
		(fp_line
			(start 0.2794 -0.1016)
			(end 0.2794 0.9906)
			(stroke
				(width 0.1)
				(type default)
			)
			(layer "B.Fab")
		)
		(fp_line
			(start 0.2794 0.9906)
			(end -0.2794 0.9906)
			(stroke
				(width 0.1)
				(type default)
			)
			(layer "B.Fab")
		)
		(pad "1" smd rect
			(at 0 0 180)
			(size 0.508 0.508)
			(layers "B.Cu" "B.Mask" "B.Paste")
			(net "P3V3_STBY")
		)
		(pad "2" smd rect
			(at 0 0.889 180)
			(size 0.508 0.508)
			(layers "B.Cu" "B.Mask" "B.Paste")
			(net "SPI_BMC_BT_CS_N")
		)
		(zone
			(layer "B.Cu")
			(hatch none 0.5)
			(connect_pads
				(clearance 0)
			)
			(min_thickness 0.25)
			(keepout
				(tracks allowed)
				(vias not_allowed)
				(pads allowed)
				(copperpour not_allowed)
				(footprints allowed)
			)
			(placement
				(enabled no)
				(sheetname "")
			)
			(fill
				(thermal_gap 0.5)
				(thermal_bridge_width 0.5)
				(island_removal_mode 0)
			)
			(polygon
				(pts
					(xy 367.900712 -37.602922) (xy 367.392712 -37.602922) (xy 367.392712 -37.221922) (xy 367.900712 -37.221922)
				)
			)
		)
		(zone
			(layer "B.Cu")
			(hatch none 0.5)
			(connect_pads
				(clearance 0)
			)
			(min_thickness 0.25)
			(keepout
				(tracks not_allowed)
				(vias allowed)
				(pads allowed)
				(copperpour not_allowed)
				(footprints allowed)
			)
			(placement
				(enabled no)
				(sheetname "")
			)
			(fill
				(thermal_gap 0.5)
				(thermal_bridge_width 0.5)
				(island_removal_mode 0)
			)
			(polygon
				(pts
					(xy 367.900712 -37.221922) (xy 367.392712 -37.221922) (xy 367.392712 -37.602922) (xy 367.900712 -37.602922)
				)
			)
		)
	)
	(footprint ""
		(layer "B.Cu")
		(at 454.453752 -144.455896)
		(property "Reference" "R9A17"
			(at 0 0 0)
			(layer "B.SilkS")
			(hide yes)
			(effects
				(font
					(size 1.27 1.27)
				)
				(justify mirror)
			)
		)
		(property "Value" ""
			(at 0 0 0)
			(layer "B.Fab")
			(effects
				(font
					(size 1.27 1.27)
				)
				(justify mirror)
			)
		)
		(duplicate_pad_numbers_are_jumpers no)
		(fp_poly
			(pts
				(xy 0.2794 -0.1016) (xy -0.2794 -0.1016) (xy -0.2794 0.9906) (xy 0.2794 0.9906)
			)
			(stroke
				(width 0)
				(type default)
			)
			(fill no)
			(layer "B.CrtYd")
		)
		(fp_line
			(start -0.2794 -0.1016)
			(end 0.2794 -0.1016)
			(stroke
				(width 0.1)
				(type default)
			)
			(layer "B.Fab")
		)
		(fp_line
			(start -0.2794 0.9906)
			(end -0.2794 -0.1016)
			(stroke
				(width 0.1)
				(type default)
			)
			(layer "B.Fab")
		)
		(fp_line
			(start 0.2794 -0.1016)
			(end 0.2794 0.9906)
			(stroke
				(width 0.1)
				(type default)
			)
			(layer "B.Fab")
		)
		(fp_line
			(start 0.2794 0.9906)
			(end -0.2794 0.9906)
			(stroke
				(width 0.1)
				(type default)
			)
			(layer "B.Fab")
		)
		(pad "1" smd rect
			(at 0 0 180)
			(size 0.508 0.508)
			(layers "B.Cu" "B.Mask" "B.Paste")
			(net "XDP_ITP_PMODE")
		)
		(pad "2" smd rect
			(at 0 0.889 180)
			(size 0.508 0.508)
			(layers "B.Cu" "B.Mask" "B.Paste")
			(net "P1V05_PCH_STBY")
		)
		(zone
			(layer "B.Cu")
			(hatch none 0.5)
			(connect_pads
				(clearance 0)
			)
			(min_thickness 0.25)
			(keepout
				(tracks allowed)
				(vias not_allowed)
				(pads allowed)
				(copperpour not_allowed)
				(footprints allowed)
			)
			(placement
				(enabled no)
				(sheetname "")
			)
			(fill
				(thermal_gap 0.5)
				(thermal_bridge_width 0.5)
				(island_removal_mode 0)
			)
			(polygon
				(pts
					(xy 454.707752 -144.201896) (xy 454.199752 -144.201896) (xy 454.199752 -143.820896) (xy 454.707752 -143.820896)
				)
			)
		)
		(zone
			(layer "B.Cu")
			(hatch none 0.5)
			(connect_pads
				(clearance 0)
			)
			(min_thickness 0.25)
			(keepout
				(tracks not_allowed)
				(vias allowed)
				(pads allowed)
				(copperpour not_allowed)
				(footprints allowed)
			)
			(placement
				(enabled no)
				(sheetname "")
			)
			(fill
				(thermal_gap 0.5)
				(thermal_bridge_width 0.5)
				(island_removal_mode 0)
			)
			(polygon
				(pts
					(xy 454.707752 -143.820896) (xy 454.199752 -143.820896) (xy 454.199752 -144.201896) (xy 454.707752 -144.201896)
				)
			)
		)
	)
)
